# T6G (Grand Teton) — schematic netlist excerpt (pin names and nets, part order shuffled) for the footprints in the layout excerpt that follows; sources: Cadence DE-HDL packaged netlist, KiCad conversion of 04192023_DAF0TMB3IC0_F0TG_MB_C_brd_V02_OCP.brd

R1504  Q_RES  30K 1% CHIP  pkg 0402LF  page 29 : A = PVDD18_S5_P0 ; B = ESPI_CPU0_D1
R3492  Q_RES  54.9K 1% CHIP  pkg 0402LF  page 129 : A = P3V3_AUX ; B = GPU_FPGA_EROT_RST_BUF_R_N

(kicad_pcb
	(version 20260206)
	(generator "pcbnew")
	(generator_version "10.0")
	(general
		(thickness 1.6)
		(legacy_teardrops no)
	)
	(paper "A4")
	(title_block
		(title "04192023_DAF0TMB3IC0_F0TG_MB_C_brd_V02_OCP.brd")
		(comment 1 "Grand Teton / footprints 4647-4648 of 8354")
	)
	(layers
		(0 "F.Cu" signal "TOP")
		(4 "In1.Cu" signal "GND")
		(6 "In2.Cu" signal "IN1")
		(8 "In3.Cu" signal "GND1")
		(10 "In4.Cu" signal "IN2")
		(12 "In5.Cu" signal "GND2")
		(14 "In6.Cu" signal "IN3")
		(16 "In7.Cu" signal "GND3")
		(18 "In8.Cu" signal "VCC")
		(20 "In9.Cu" signal "VCC1")
		(22 "In10.Cu" signal "GND4")
		(24 "In11.Cu" signal "IN4")
		(26 "In12.Cu" signal "GND5")
		(28 "In13.Cu" signal "IN5")
		(30 "In14.Cu" signal "GND6")
		(32 "In15.Cu" signal "IN6")
		(34 "In16.Cu" signal "GND7")
		(2 "B.Cu" signal "BOTTOM")
		(9 "F.Adhes" user "F.Adhesive")
		(11 "B.Adhes" user "B.Adhesive")
		(13 "F.Paste" user "Package Geometry/Pastemask Top")
		(15 "B.Paste" user "Package Geometry/Pastemask Bottom")
		(5 "F.SilkS" user "Ref Des/Silkscreen Top")
		(7 "B.SilkS" user "Ref Des/Silkscreen Bottom")
		(1 "F.Mask" user "Board Geometry/Soldermask Top")
		(3 "B.Mask" user "Board Geometry/Soldermask Bottom")
		(17 "Dwgs.User" user "User.Drawings")
		(19 "Cmts.User" user "User.Comments")
		(21 "Eco1.User" user "User.Eco1")
		(23 "Eco2.User" user "User.Eco2")
		(25 "Edge.Cuts" user "Board Geometry/Outline")
		(27 "Margin" user)
		(31 "F.CrtYd" user "Package Geometry/Place Bound Top")
		(29 "B.CrtYd" user "Package Geometry/Place Bound Bottom")
		(35 "F.Fab" user "Ref Des/Assembly Top")
		(33 "B.Fab" user "Ref Des/Assembly Bottom")
	)
	(footprint ""
		(layer "F.Cu")
		(at 103.505 -418.973 180)
		(property "Reference" "R3492"
			(at 0 0 180)
			(layer "F.SilkS")
			(hide yes)
			(effects
				(font
					(size 1.27 1.27)
				)
			)
		)
		(property "Value" ""
			(at 0 0 180)
			(layer "F.Fab")
			(effects
				(font
					(size 1.27 1.27)
				)
			)
		)
		(duplicate_pad_numbers_are_jumpers no)
		(fp_line
			(start 0.7874 0.4064)
			(end -0.7874 0.4064)
			(stroke
				(width 0.1524)
				(type default)
			)
			(layer "F.SilkS")
		)
		(fp_line
			(start 0.7874 -0.4064)
			(end 0.7874 0.4064)
			(stroke
				(width 0.1524)
				(type default)
			)
			(layer "F.SilkS")
		)
		(fp_line
			(start -0.7874 0.4064)
			(end -0.7874 -0.4064)
			(stroke
				(width 0.1524)
				(type default)
			)
			(layer "F.SilkS")
		)
		(fp_line
			(start -0.7874 -0.4064)
			(end 0.7874 -0.4064)
			(stroke
				(width 0.1524)
				(type default)
			)
			(layer "F.SilkS")
		)
		(fp_line
			(start 0.67945 0.3048)
			(end 0.120396 0.3048)
			(stroke
				(width 0.1)
				(type default)
			)
			(layer "F.Fab")
		)
		(fp_line
			(start 0.67945 -0.3048)
			(end 0.67945 0.3048)
			(stroke
				(width 0.1)
				(type default)
			)
			(layer "F.Fab")
		)
		(fp_line
			(start 0.12065 -0.2794)
			(end 0.12065 -0.3048)
			(stroke
				(width 0.1)
				(type default)
			)
			(layer "F.Fab")
		)
		(fp_line
			(start 0.12065 -0.3048)
			(end 0.67945 -0.3048)
			(stroke
				(width 0.1)
				(type default)
			)
			(layer "F.Fab")
		)
		(fp_line
			(start 0.120396 0.3048)
			(end 0.120396 0.2794)
			(stroke
				(width 0.1)
				(type default)
			)
			(layer "F.Fab")
		)
		(fp_line
			(start 0.120396 0.2794)
			(end -0.12065 0.2794)
			(stroke
				(width 0.1)
				(type default)
			)
			(layer "F.Fab")
		)
		(fp_line
			(start -0.12065 0.3048)
			(end -0.67945 0.3048)
			(stroke
				(width 0.1)
				(type default)
			)
			(layer "F.Fab")
		)
		(fp_line
			(start -0.12065 0.2794)
			(end -0.12065 0.3048)
			(stroke
				(width 0.1)
				(type default)
			)
			(layer "F.Fab")
		)
		(fp_line
			(start -0.12065 -0.2794)
			(end 0.12065 -0.2794)
			(stroke
				(width 0.1)
				(type default)
			)
			(layer "F.Fab")
		)
		(fp_line
			(start -0.12065 -0.305054)
			(end -0.12065 -0.2794)
			(stroke
				(width 0.1)
				(type default)
			)
			(layer "F.Fab")
		)
		(fp_line
			(start -0.67945 0.3048)
			(end -0.67945 -0.305054)
			(stroke
				(width 0.1)
				(type default)
			)
			(layer "F.Fab")
		)
		(fp_line
			(start -0.67945 -0.305054)
			(end -0.12065 -0.305054)
			(stroke
				(width 0.1)
				(type default)
			)
			(layer "F.Fab")
		)
		(pad "1" smd circle
			(at -0.40005 0 180)
			(size 0 0)
			(layers "F.Cu" "F.Mask" "F.Paste")
			(net "P3V3_AUX")
		)
		(pad "2" smd circle
			(at 0.40005 0 180)
			(size 0 0)
			(layers "F.Cu" "F.Mask" "F.Paste")
			(net "GPU_FPGA_EROT_RST_BUF_R_N")
		)
	)
	(footprint ""
		(layer "F.Cu")
		(at 397.125952 -323.45503)
		(property "Reference" "R1504"
			(at 0 0 0)
			(layer "F.SilkS")
			(hide yes)
			(effects
				(font
					(size 1.27 1.27)
				)
			)
		)
		(property "Value" ""
			(at 0 0 0)
			(layer "F.Fab")
			(effects
				(font
					(size 1.27 1.27)
				)
			)
		)
		(duplicate_pad_numbers_are_jumpers no)
		(fp_line
			(start -0.7874 -0.4064)
			(end 0.7874 -0.4064)
			(stroke
				(width 0.1524)
				(type default)
			)
			(layer "F.SilkS")
		)
		(fp_line
			(start -0.7874 0.4064)
			(end -0.7874 -0.4064)
			(stroke
				(width 0.1524)
				(type default)
			)
			(layer "F.SilkS")
		)
		(fp_line
			(start 0.7874 -0.4064)
			(end 0.7874 0.4064)
			(stroke
				(width 0.1524)
				(type default)
			)
			(layer "F.SilkS")
		)
		(fp_line
			(start 0.7874 0.4064)
			(end -0.7874 0.4064)
			(stroke
				(width 0.1524)
				(type default)
			)
			(layer "F.SilkS")
		)
		(fp_line
			(start -0.67945 -0.305054)
			(end -0.12065 -0.305054)
			(stroke
				(width 0.1)
				(type default)
			)
			(layer "F.Fab")
		)
		(fp_line
			(start -0.67945 0.3048)
			(end -0.67945 -0.305054)
			(stroke
				(width 0.1)
				(type default)
			)
			(layer "F.Fab")
		)
		(fp_line
			(start -0.12065 -0.305054)
			(end -0.12065 -0.2794)
			(stroke
				(width 0.1)
				(type default)
			)
			(layer "F.Fab")
		)
		(fp_line
			(start -0.12065 -0.2794)
			(end 0.12065 -0.2794)
			(stroke
				(width 0.1)
				(type default)
			)
			(layer "F.Fab")
		)
		(fp_line
			(start -0.12065 0.2794)
			(end -0.12065 0.3048)
			(stroke
				(width 0.1)
				(type default)
			)
			(layer "F.Fab")
		)
		(fp_line
			(start -0.12065 0.3048)
			(end -0.67945 0.3048)
			(stroke
				(width 0.1)
				(type default)
			)
			(layer "F.Fab")
		)
		(fp_line
			(start 0.120396 0.2794)
			(end -0.12065 0.2794)
			(stroke
				(width 0.1)
				(type default)
			)
			(layer "F.Fab")
		)
		(fp_line
			(start 0.120396 0.3048)
			(end 0.120396 0.2794)
			(stroke
				(width 0.1)
				(type default)
			)
			(layer "F.Fab")
		)
		(fp_line
			(start 0.12065 -0.3048)
			(end 0.67945 -0.3048)
			(stroke
				(width 0.1)
				(type default)
			)
			(layer "F.Fab")
		)
		(fp_line
			(start 0.12065 -0.2794)
			(end 0.12065 -0.3048)
			(stroke
				(width 0.1)
				(type default)
			)
			(layer "F.Fab")
		)
		(fp_line
			(start 0.67945 -0.3048)
			(end 0.67945 0.3048)
			(stroke
				(width 0.1)
				(type default)
			)
			(layer "F.Fab")
		)
		(fp_line
			(start 0.67945 0.3048)
			(end 0.120396 0.3048)
			(stroke
				(width 0.1)
				(type default)
			)
			(layer "F.Fab")
		)
		(pad "1" smd circle
			(at -0.40005 0)
			(size 0 0)
			(layers "F.Cu" "F.Mask" "F.Paste")
			(net "PVDD18_S5_P0")
		)
		(pad "2" smd circle
			(at 0.40005 0)
			(size 0 0)
			(layers "F.Cu" "F.Mask" "F.Paste")
			(net "ESPI_CPU0_D1")
		)
	)
)
